(kicad_pcb
	(version 20260206)
	(generator "pcbnew")
	(generator_version "10.0")
	(general
		(thickness 1.6)
		(legacy_teardrops no)
	)
	(paper "A4")
	(title_block
		(title "panther-plus-userver — 13130-1b_20150205.brd")
		(comment 1 "Honey Badger (Wiwynn) / footprints 129-137 of 1509")
	)
	(layers
		(0 "F.Cu" signal "TOP")
		(4 "In1.Cu" signal "L2")
		(6 "In2.Cu" signal "L3")
		(8 "In3.Cu" signal "L4")
		(10 "In4.Cu" signal "L5")
		(12 "In5.Cu" signal "L6")
		(14 "In6.Cu" signal "L7")
		(16 "In7.Cu" signal "L8")
		(18 "In8.Cu" signal "L9")
		(20 "In9.Cu" signal "L10")
		(22 "In10.Cu" signal "L11")
		(2 "B.Cu" signal "BOTTOM")
		(9 "F.Adhes" user "F.Adhesive")
		(11 "B.Adhes" user "B.Adhesive")
		(13 "F.Paste" user "Package Geometry/Pastemask Top")
		(15 "B.Paste" user "Package Geometry/Pastemask Bottom")
		(5 "F.SilkS" user "Ref Des/Silkscreen Top")
		(7 "B.SilkS" user "Ref Des/Silkscreen Bottom")
		(1 "F.Mask" user "Board Geometry/Soldermask Top")
		(3 "B.Mask" user "Board Geometry/Soldermask Bottom")
		(17 "Dwgs.User" user "User.Drawings")
		(19 "Cmts.User" user "User.Comments")
		(21 "Eco1.User" user "User.Eco1")
		(23 "Eco2.User" user "User.Eco2")
		(25 "Edge.Cuts" user "Board Geometry/Outline")
		(27 "Margin" user)
		(31 "F.CrtYd" user "Package Geometry/Place Bound Top")
		(29 "B.CrtYd" user "Package Geometry/Place Bound Bottom")
		(35 "F.Fab" user "Ref Des/Assembly Top")
		(33 "B.Fab" user "Ref Des/Assembly Bottom")
	)
	(footprint ""
		(layer "F.Cu")
		(at 167.132 -41.656)
		(property "Reference" "OSC1"
			(at 0 0 0)
			(layer "F.SilkS")
			(hide yes)
			(effects
				(font
					(size 1.27 1.27)
				)
			)
		)
		(property "Value" "OSC-5MHZ-GP"
			(at 0 -4.182618 0)
			(unlocked yes)
			(layer "F.Fab")
			(hide yes)
			(effects
				(font
					(size 1.016 1.016)
					(thickness 0.1524)
				)
			)
		)
		(property "Device Type" "OSC-3225-4P-3H48"
			(at 0 -5.706618 0)
			(unlocked yes)
			(layer "F.Fab")
			(hide yes)
			(effects
				(font
					(size 1.016 1.016)
					(thickness 0.1524)
				)
			)
		)
		(duplicate_pad_numbers_are_jumpers no)
		(fp_poly
			(pts
				(xy -2.2987 1.2192) (xy -2.2987 0.3556) (xy -1.8669 0.7874)
			)
			(stroke
				(width 0)
				(type default)
			)
			(fill yes)
			(layer "F.SilkS")
		)
		(fp_rect
			(start -1.8669 1.4986)
			(end 1.8669 -1.4986)
			(stroke
				(width 0)
				(type default)
			)
			(fill no)
			(layer "F.CrtYd")
		)
		(fp_rect
			(start -1.8669 1.4986)
			(end 1.8669 -1.4986)
			(stroke
				(width 0)
				(type default)
			)
			(fill no)
			(layer "F.Fab")
		)
		(pad "1" smd rect
			(at -1.107948 0.824992)
			(size 1.27 0.9144)
			(layers "F.Cu" "F.Mask" "F.Paste")
			(net "OSC_5M_EN")
		)
		(pad "2" smd rect
			(at 1.107948 0.824992)
			(size 1.27 0.9144)
			(layers "F.Cu" "F.Mask" "F.Paste")
			(net "GND")
		)
		(pad "3" smd rect
			(at 1.107948 -0.824992)
			(size 1.27 0.9144)
			(layers "F.Cu" "F.Mask" "F.Paste")
			(net "OSC_5M_CLK_R")
		)
		(pad "4" smd rect
			(at -1.107948 -0.824992)
			(size 1.27 0.9144)
			(layers "F.Cu" "F.Mask" "F.Paste")
			(net "P3V3_STBY")
		)
		(zone
			(layer "F.Cu")
			(hatch none 0.5)
			(connect_pads
				(clearance 0)
			)
			(min_thickness 0.25)
			(keepout
				(tracks not_allowed)
				(vias allowed)
				(pads allowed)
				(copperpour not_allowed)
				(footprints allowed)
			)
			(placement
				(enabled no)
				(sheetname "")
			)
			(fill
				(thermal_gap 0.5)
				(thermal_bridge_width 0.5)
				(island_removal_mode 0)
			)
			(polygon
				(pts
					(xy 166.984172 -41.613328) (xy 167.279828 -41.613328) (xy 167.279828 -41.698672) (xy 166.984172 -41.698672)
				)
			)
		)
		(zone
			(layer "F.Cu")
			(hatch none 0.5)
			(connect_pads
				(clearance 0)
			)
			(min_thickness 0.25)
			(keepout
				(tracks allowed)
				(vias not_allowed)
				(pads allowed)
				(copperpour not_allowed)
				(footprints allowed)
			)
			(placement
				(enabled no)
				(sheetname "")
			)
			(fill
				(thermal_gap 0.5)
				(thermal_bridge_width 0.5)
				(island_removal_mode 0)
			)
			(polygon
				(pts
					(xy 166.659052 -40.373808) (xy 166.659052 -41.288208) (xy 165.389052 -41.288208) (xy 165.389052 -42.023792)
					(xy 166.659052 -42.023792) (xy 166.659052 -42.938192) (xy 167.604948 -42.938192) (xy 167.604948 -42.023792)
					(xy 168.874948 -42.023792) (xy 168.874948 -41.288208) (xy 167.604948 -41.288208) (xy 167.604948 -40.373808)
				)
			)
		)
	)
	(footprint ""
		(layer "F.Cu")
		(at 63.119 -56.769)
		(property "Reference" "PC144"
			(at 0 0 0)
			(layer "F.SilkS")
			(hide yes)
			(effects
				(font
					(size 1.27 1.27)
				)
			)
		)
		(property "Value" "SC47U6D3V5MX-1-GP"
			(at -0.0762 -6.1214 0)
			(unlocked yes)
			(layer "F.Fab")
			(hide yes)
			(effects
				(font
					(size 1.016 1.016)
					(thickness 0.1524)
				)
			)
		)
		(property "Device Type" "C805H54"
			(at -0.0762 -8.1534 0)
			(unlocked yes)
			(layer "F.Fab")
			(hide yes)
			(effects
				(font
					(size 1.016 1.016)
					(thickness 0.1524)
				)
			)
		)
		(duplicate_pad_numbers_are_jumpers no)
		(fp_line
			(start 0.6096 0)
			(end -0.6096 0)
			(stroke
				(width 0.3048)
				(type default)
			)
			(layer "F.SilkS")
		)
		(fp_poly
			(pts
				(xy -0.9017 1.4351) (xy 0.9017 1.4351) (xy 0.9017 -1.4351) (xy -0.9017 -1.4351)
			)
			(stroke
				(width 0)
				(type default)
			)
			(fill no)
			(layer "F.CrtYd")
		)
		(fp_poly
			(pts
				(xy 0.9017 1.4351) (xy 0.9017 -1.4351) (xy -0.9017 -1.4351) (xy -0.9017 1.4351)
			)
			(stroke
				(width 0)
				(type default)
			)
			(fill no)
			(layer "F.Fab")
		)
		(pad "1" smd rect
			(at 0 -0.8382)
			(size 1.5494 0.9398)
			(layers "F.Cu" "F.Mask" "F.Paste")
			(net "PVCCP")
		)
		(pad "2" smd rect
			(at 0 0.8382)
			(size 1.5494 0.9398)
			(layers "F.Cu" "F.Mask" "F.Paste")
			(net "GND")
		)
	)
	(footprint ""
		(layer "F.Cu")
		(at 12.9286 -62.0776 90)
		(property "Reference" "PR41"
			(at 0 0 90)
			(layer "F.SilkS")
			(hide yes)
			(effects
				(font
					(size 1.27 1.27)
				)
			)
		)
		(property "Value" "0R2J-2-GP"
			(at 1.7907 -1.1176 90)
			(unlocked yes)
			(layer "F.Fab")
			(hide yes)
			(effects
				(font
					(size 1.016 1.016)
					(thickness 0.1524)
				)
			)
		)
		(property "Device Type" "R402H16"
			(at 1.7907 -2.6416 90)
			(unlocked yes)
			(layer "F.Fab")
			(hide yes)
			(effects
				(font
					(size 1.016 1.016)
					(thickness 0.1524)
				)
			)
		)
		(duplicate_pad_numbers_are_jumpers no)
		(fp_rect
			(start -0.381 0.8382)
			(end 0.381 -0.8382)
			(stroke
				(width 0)
				(type default)
			)
			(fill no)
			(layer "F.CrtYd")
		)
		(fp_rect
			(start -0.381 0.8382)
			(end 0.381 -0.8382)
			(stroke
				(width 0)
				(type default)
			)
			(fill no)
			(layer "F.Fab")
		)
		(pad "1" smd custom
			(at 0 -0.4318 90)
			(size 0.127 0.127)
			(layers "F.Cu" "F.Mask" "F.Paste")
			(net "TP_PVCCP_VDIO")
			(options
				(clearance outline)
				(anchor circle)
			)
			(primitives
				(gr_poly
					(pts
						(arc
							(start -0.2032 -0.2794)
							(mid -0.239121 -0.264521)
							(end -0.254 -0.2286)
						)
						(arc
							(start -0.254 0.2286)
							(mid -0.239121 0.264521)
							(end -0.2032 0.2794)
						)
						(arc
							(start 0.2032 0.2794)
							(mid 0.239121 0.264521)
							(end 0.254 0.2286)
						)
						(arc
							(start 0.254 -0.2286)
							(mid 0.239121 -0.264521)
							(end 0.2032 -0.2794)
						)
					)
					(width 0)
					(fill yes)
				)
			)
		)
		(pad "2" smd custom
			(at 0 0.4318 90)
			(size 0.127 0.127)
			(layers "F.Cu" "F.Mask" "F.Paste")
			(net "SVID_CPU_DATA")
			(options
				(clearance outline)
				(anchor circle)
			)
			(primitives
				(gr_poly
					(pts
						(arc
							(start -0.2032 -0.2794)
							(mid -0.239121 -0.264521)
							(end -0.254 -0.2286)
						)
						(arc
							(start -0.254 0.2286)
							(mid -0.239121 0.264521)
							(end -0.2032 0.2794)
						)
						(arc
							(start 0.2032 0.2794)
							(mid 0.239121 0.264521)
							(end 0.254 0.2286)
						)
						(arc
							(start 0.254 -0.2286)
							(mid 0.239121 -0.264521)
							(end 0.2032 -0.2794)
						)
					)
					(width 0)
					(fill yes)
				)
			)
		)
	)
	(footprint ""
		(layer "F.Cu")
		(at 10.668 -51.7398 90)
		(property "Reference" "C60"
			(at 0 0 90)
			(layer "F.SilkS")
			(hide yes)
			(effects
				(font
					(size 1.27 1.27)
				)
			)
		)
		(property "Value" "SCD01U16V2KX-3GP"
			(at 1.1811 -2.7051 90)
			(unlocked yes)
			(layer "F.Fab")
			(hide yes)
			(effects
				(font
					(size 1.016 1.016)
					(thickness 0.1524)
				)
			)
		)
		(property "Device Type" "C402H22"
			(at 1.1811 -4.2291 90)
			(unlocked yes)
			(layer "F.Fab")
			(hide yes)
			(effects
				(font
					(size 1.016 1.016)
					(thickness 0.1524)
				)
			)
		)
		(duplicate_pad_numbers_are_jumpers no)
		(fp_rect
			(start -0.381 0.7366)
			(end 0.381 -0.7366)
			(stroke
				(width 0)
				(type default)
			)
			(fill no)
			(layer "F.CrtYd")
		)
		(fp_rect
			(start -0.381 0.7366)
			(end 0.381 -0.7366)
			(stroke
				(width 0)
				(type default)
			)
			(fill no)
			(layer "F.Fab")
		)
		(pad "1" smd custom
			(at 0 -0.4572 90)
			(size 0.1143 0.1143)
			(layers "F.Cu" "F.Mask" "F.Paste")
			(net "SATA3_TX_DN1")
			(options
				(clearance outline)
				(anchor circle)
			)
			(primitives
				(gr_poly
					(pts
						(arc
							(start -0.254 -0.1778)
							(mid -0.239121 -0.213721)
							(end -0.2032 -0.2286)
						)
						(arc
							(start 0.2032 -0.2286)
							(mid 0.239121 -0.213721)
							(end 0.254 -0.1778)
						)
						(arc
							(start 0.254 0.1778)
							(mid 0.239121 0.213721)
							(end 0.2032 0.2286)
						)
						(arc
							(start -0.2032 0.2286)
							(mid -0.239121 0.213721)
							(end -0.254 0.1778)
						)
					)
					(width 0)
					(fill yes)
				)
			)
		)
		(pad "2" smd custom
			(at 0 0.4572 90)
			(size 0.1143 0.1143)
			(layers "F.Cu" "F.Mask" "F.Paste")
			(net "P2E_CPU_NGFF_TX_DN12")
			(options
				(clearance outline)
				(anchor circle)
			)
			(primitives
				(gr_poly
					(pts
						(arc
							(start -0.254 -0.1778)
							(mid -0.239121 -0.213721)
							(end -0.2032 -0.2286)
						)
						(arc
							(start 0.2032 -0.2286)
							(mid 0.239121 -0.213721)
							(end 0.254 -0.1778)
						)
						(arc
							(start 0.254 0.1778)
							(mid 0.239121 0.213721)
							(end 0.2032 0.2286)
						)
						(arc
							(start -0.2032 0.2286)
							(mid -0.239121 0.213721)
							(end -0.254 0.1778)
						)
					)
					(width 0)
					(fill yes)
				)
			)
		)
	)
	(footprint ""
		(layer "F.Cu")
		(at 194.691 -31.623)
		(property "Reference" "PR139"
			(at 0 0 0)
			(layer "F.SilkS")
			(hide yes)
			(effects
				(font
					(size 1.27 1.27)
				)
			)
		)
		(property "Value" "4K12R2F-GP"
			(at 1.7907 -1.1176 0)
			(unlocked yes)
			(layer "F.Fab")
			(hide yes)
			(effects
				(font
					(size 1.016 1.016)
					(thickness 0.1524)
				)
			)
		)
		(property "Device Type" "R402H16"
			(at 1.7907 -2.6416 0)
			(unlocked yes)
			(layer "F.Fab")
			(hide yes)
			(effects
				(font
					(size 1.016 1.016)
					(thickness 0.1524)
				)
			)
		)
		(duplicate_pad_numbers_are_jumpers no)
		(fp_rect
			(start -0.381 0.8382)
			(end 0.381 -0.8382)
			(stroke
				(width 0)
				(type default)
			)
			(fill no)
			(layer "F.CrtYd")
		)
		(fp_rect
			(start -0.381 0.8382)
			(end 0.381 -0.8382)
			(stroke
				(width 0)
				(type default)
			)
			(fill no)
			(layer "F.Fab")
		)
		(pad "1" smd custom
			(at 0 -0.4318)
			(size 0.127 0.127)
			(layers "F.Cu" "F.Mask" "F.Paste")
			(net "VR_PVDDR_A_PROG1")
			(options
				(clearance outline)
				(anchor circle)
			)
			(primitives
				(gr_poly
					(pts
						(arc
							(start -0.2032 -0.2794)
							(mid -0.239121 -0.264521)
							(end -0.254 -0.2286)
						)
						(arc
							(start -0.254 0.2286)
							(mid -0.239121 0.264521)
							(end -0.2032 0.2794)
						)
						(arc
							(start 0.2032 0.2794)
							(mid 0.239121 0.264521)
							(end 0.254 0.2286)
						)
						(arc
							(start 0.254 -0.2286)
							(mid 0.239121 -0.264521)
							(end 0.2032 -0.2794)
						)
					)
					(width 0)
					(fill yes)
				)
			)
		)
		(pad "2" smd custom
			(at 0 0.4318)
			(size 0.127 0.127)
			(layers "F.Cu" "F.Mask" "F.Paste")
			(net "GND")
			(options
				(clearance outline)
				(anchor circle)
			)
			(primitives
				(gr_poly
					(pts
						(arc
							(start -0.2032 -0.2794)
							(mid -0.239121 -0.264521)
							(end -0.254 -0.2286)
						)
						(arc
							(start -0.254 0.2286)
							(mid -0.239121 0.264521)
							(end -0.2032 0.2794)
						)
						(arc
							(start 0.2032 0.2794)
							(mid 0.239121 0.264521)
							(end 0.254 0.2286)
						)
						(arc
							(start 0.254 -0.2286)
							(mid 0.239121 -0.264521)
							(end 0.2032 -0.2794)
						)
					)
					(width 0)
					(fill yes)
				)
			)
		)
	)
	(footprint ""
		(layer "F.Cu")
		(at 49.3522 -34.925 180)
		(property "Reference" "R109"
			(at 0 0 180)
			(layer "F.SilkS")
			(hide yes)
			(effects
				(font
					(size 1.27 1.27)
				)
			)
		)
		(property "Value" "33R2F-3-GP"
			(at 0.064008 -3.993896 180)
			(unlocked yes)
			(layer "F.Fab")
			(hide yes)
			(effects
				(font
					(size 1.016 1.016)
					(thickness 0.1524)
				)
			)
		)
		(property "Device Type" "R402H16"
			(at 0.064008 -5.517896 180)
			(unlocked yes)
			(layer "F.Fab")
			(hide yes)
			(effects
				(font
					(size 1.016 1.016)
					(thickness 0.1524)
				)
			)
		)
		(duplicate_pad_numbers_are_jumpers no)
		(fp_rect
			(start -0.381 0.8382)
			(end 0.381 -0.8382)
			(stroke
				(width 0)
				(type default)
			)
			(fill no)
			(layer "F.CrtYd")
		)
		(fp_rect
			(start -0.381 0.8382)
			(end 0.381 -0.8382)
			(stroke
				(width 0)
				(type default)
			)
			(fill no)
			(layer "F.Fab")
		)
		(pad "1" smd custom
			(at 0 -0.4318 180)
			(size 0.127 0.127)
			(layers "F.Cu" "F.Mask" "F.Paste")
			(net "SPI_SCLK_R_1")
			(options
				(clearance outline)
				(anchor circle)
			)
			(primitives
				(gr_poly
					(pts
						(arc
							(start -0.2032 -0.2794)
							(mid -0.239121 -0.264521)
							(end -0.254 -0.2286)
						)
						(arc
							(start -0.254 0.2286)
							(mid -0.239121 0.264521)
							(end -0.2032 0.2794)
						)
						(arc
							(start 0.2032 0.2794)
							(mid 0.239121 0.264521)
							(end 0.254 0.2286)
						)
						(arc
							(start 0.254 -0.2286)
							(mid 0.239121 -0.264521)
							(end 0.2032 -0.2794)
						)
					)
					(width 0)
					(fill yes)
				)
			)
		)
		(pad "2" smd custom
			(at 0 0.4318 180)
			(size 0.127 0.127)
			(layers "F.Cu" "F.Mask" "F.Paste")
			(net "SPI_CPU_SCLK")
			(options
				(clearance outline)
				(anchor circle)
			)
			(primitives
				(gr_poly
					(pts
						(arc
							(start -0.2032 -0.2794)
							(mid -0.239121 -0.264521)
							(end -0.254 -0.2286)
						)
						(arc
							(start -0.254 0.2286)
							(mid -0.239121 0.264521)
							(end -0.2032 0.2794)
						)
						(arc
							(start 0.2032 0.2794)
							(mid 0.239121 0.264521)
							(end 0.254 0.2286)
						)
						(arc
							(start 0.254 -0.2286)
							(mid 0.239121 -0.264521)
							(end 0.2032 -0.2794)
						)
					)
					(width 0)
					(fill yes)
				)
			)
		)
	)
	(footprint ""
		(layer "F.Cu")
		(at 20.066 -63.4492 90)
		(property "Reference" "PC15"
			(at 0 0 90)
			(layer "F.SilkS")
			(hide yes)
			(effects
				(font
					(size 1.27 1.27)
				)
			)
		)
		(property "Value" "SCD068U16V2KX-GP"
			(at 1.8923 -1.2065 90)
			(unlocked yes)
			(layer "F.Fab")
			(hide yes)
			(effects
				(font
					(size 1.016 1.016)
					(thickness 0.1524)
				)
			)
		)
		(property "Device Type" "C402H22"
			(at 1.8923 -2.7305 90)
			(unlocked yes)
			(layer "F.Fab")
			(hide yes)
			(effects
				(font
					(size 1.016 1.016)
					(thickness 0.1524)
				)
			)
		)
		(duplicate_pad_numbers_are_jumpers no)
		(fp_rect
			(start -0.381 0.7366)
			(end 0.381 -0.7366)
			(stroke
				(width 0)
				(type default)
			)
			(fill no)
			(layer "F.CrtYd")
		)
		(fp_rect
			(start -0.381 0.7366)
			(end 0.381 -0.7366)
			(stroke
				(width 0)
				(type default)
			)
			(fill no)
			(layer "F.Fab")
		)
		(pad "1" smd custom
			(at 0 -0.4572 90)
			(size 0.1143 0.1143)
			(layers "F.Cu" "F.Mask" "F.Paste")
			(net "VR_PVNN_VSEN")
			(options
				(clearance outline)
				(anchor circle)
			)
			(primitives
				(gr_poly
					(pts
						(arc
							(start -0.254 -0.1778)
							(mid -0.239121 -0.213721)
							(end -0.2032 -0.2286)
						)
						(arc
							(start 0.2032 -0.2286)
							(mid 0.239121 -0.213721)
							(end 0.254 -0.1778)
						)
						(arc
							(start 0.254 0.1778)
							(mid 0.239121 0.213721)
							(end 0.2032 0.2286)
						)
						(arc
							(start -0.2032 0.2286)
							(mid -0.239121 0.213721)
							(end -0.254 0.1778)
						)
					)
					(width 0)
					(fill yes)
				)
			)
		)
		(pad "2" smd custom
			(at 0 0.4572 90)
			(size 0.1143 0.1143)
			(layers "F.Cu" "F.Mask" "F.Paste")
			(net "VR_PVNN_RTN")
			(options
				(clearance outline)
				(anchor circle)
			)
			(primitives
				(gr_poly
					(pts
						(arc
							(start -0.254 -0.1778)
							(mid -0.239121 -0.213721)
							(end -0.2032 -0.2286)
						)
						(arc
							(start 0.2032 -0.2286)
							(mid 0.239121 -0.213721)
							(end 0.254 -0.1778)
						)
						(arc
							(start 0.254 0.1778)
							(mid 0.239121 0.213721)
							(end 0.2032 0.2286)
						)
						(arc
							(start -0.2032 0.2286)
							(mid -0.239121 0.213721)
							(end -0.254 0.1778)
						)
					)
					(width 0)
					(fill yes)
				)
			)
		)
	)
	(footprint ""
		(layer "F.Cu")
		(at 36.7538 -54.9656)
		(property "Reference" "PC18"
			(at 0 0 0)
			(layer "F.SilkS")
			(hide yes)
			(effects
				(font
					(size 1.27 1.27)
				)
			)
		)
		(property "Value" "SC10U25V5KX-GP"
			(at 0 -4.9022 0)
			(unlocked yes)
			(layer "F.Fab")
			(hide yes)
			(effects
				(font
					(size 1.016 1.016)
					(thickness 0.1524)
				)
			)
		)
		(property "Device Type" "C805H56"
			(at 0 -6.8072 0)
			(unlocked yes)
			(layer "F.Fab")
			(hide yes)
			(effects
				(font
					(size 1.016 1.016)
					(thickness 0.1524)
				)
			)
		)
		(duplicate_pad_numbers_are_jumpers no)
		(fp_line
			(start 0.6096 0)
			(end -0.6096 0)
			(stroke
				(width 0.3048)
				(type default)
			)
			(layer "F.SilkS")
		)
		(fp_poly
			(pts
				(xy -0.9017 1.4351) (xy 0.9017 1.4351) (xy 0.9017 -1.4351) (xy -0.9017 -1.4351)
			)
			(stroke
				(width 0)
				(type default)
			)
			(fill no)
			(layer "F.CrtYd")
		)
		(fp_poly
			(pts
				(xy 0.9017 1.4351) (xy 0.9017 -1.4351) (xy -0.9017 -1.4351) (xy -0.9017 1.4351)
			)
			(stroke
				(width 0)
				(type default)
			)
			(fill no)
			(layer "F.Fab")
		)
		(pad "1" smd rect
			(at 0 -0.8382)
			(size 1.5494 0.9398)
			(layers "F.Cu" "F.Mask" "F.Paste")
			(net "VR_FET_SW_P12V_PVCCP_PVNN")
		)
		(pad "2" smd rect
			(at 0 0.8382)
			(size 1.5494 0.9398)
			(layers "F.Cu" "F.Mask" "F.Paste")
			(net "GND")
		)
	)
	(footprint ""
		(layer "F.Cu")
		(at 167.894 -33.782 -90)
		(property "Reference" "PC83"
			(at 0 0 270)
			(layer "F.SilkS")
			(hide yes)
			(effects
				(font
					(size 1.27 1.27)
				)
			)
		)
		(property "Value" "SC22U6D3V5MX-2GP"
			(at -0.0762 -6.1214 270)
			(unlocked yes)
			(layer "F.Fab")
			(hide yes)
			(effects
				(font
					(size 1.016 1.016)
					(thickness 0.1524)
				)
			)
		)
		(property "Device Type" "C805H58"
			(at -0.0762 -8.1534 270)
			(unlocked yes)
			(layer "F.Fab")
			(hide yes)
			(effects
				(font
					(size 1.016 1.016)
					(thickness 0.1524)
				)
			)
		)
		(duplicate_pad_numbers_are_jumpers no)
		(fp_line
			(start 0.6096 0)
			(end -0.6096 0)
			(stroke
				(width 0.3048)
				(type default)
			)
			(layer "F.SilkS")
		)
		(fp_poly
			(pts
				(xy -0.9017 1.4351) (xy 0.9017 1.4351) (xy 0.9017 -1.4351) (xy -0.9017 -1.4351)
			)
			(stroke
				(width 0)
				(type default)
			)
			(fill no)
			(layer "F.CrtYd")
		)
		(fp_poly
			(pts
				(xy 0.9017 1.4351) (xy 0.9017 -1.4351) (xy -0.9017 -1.4351) (xy -0.9017 1.4351)
			)
			(stroke
				(width 0)
				(type default)
			)
			(fill no)
			(layer "F.Fab")
		)
		(pad "1" smd rect
			(at 0 -0.8382 270)
			(size 1.5494 0.9398)
			(layers "F.Cu" "F.Mask" "F.Paste")
			(net "P1V2_STBY_LDO_OUT1")
		)
		(pad "2" smd rect
			(at 0 0.8382 270)
			(size 1.5494 0.9398)
			(layers "F.Cu" "F.Mask" "F.Paste")
			(net "GND")
		)
	)
)
